# BASEBOARD_FAB2 (Tioga Pass) — schematic parts with pin connectivity, parts 4650–4650 of 4751; source: Cadence DE-HDL packaged netlist (pstxprt.dat, pstxnet.dat, pstchip.dat)

U2D1  SKX_EXT_B  IC  pkg BGA1  page 55  (pins 2367-2704 of 3647)
  DL18  VSS(169)  GROUND  = GND
  DL20  UPI2_TX_DN(2)  OUT  = TP_CPU1_UPI2_RSVD_CE12
  DL22  VSS(167)  GROUND  = GND
  DL24  VSS(166)  GROUND  = GND
  DL26  DDR4_DQS_DN(7)  BI  = M_L_DQS_DN<7>
  DL28  VSS(165)  GROUND  = GND
  DL30  VSS(164)  GROUND  = GND
  DL32  DDR5_DQS_DN(5)  BI  = M_M_DQS_DN<5>
  DL34  VSS(163)  GROUND  = GND
  DL36  VSS(162)  GROUND  = GND
  DL38  RSVD(35)  BI  = TP_CPU1_RSVD_35
  DL40  VSS(161)  GROUND  = GND
  DL42  DDR4_DQ(36)  BI  = M_L_DQ<36>
  DL44  SVIDALERT_N(1)  IN  = SVID_ALERT1_CPU1_N
  DL46  VCCD345(30)  POWER  = PVDDQ_KLM
  DL48  VCCD345(29)  POWER  = PVDDQ_KLM
  DL50  VCCD345(28)  POWER  = PVDDQ_KLM
  DL52  VCCD345(27)  POWER  = PVDDQ_KLM
  DL54  VCCD345(26)  POWER  = PVDDQ_KLM
  DL56  VCCD345(25)  POWER  = PVDDQ_KLM
  DL58  VCCD345(24)  POWER  = PVDDQ_KLM
  DL60  VCCD345(23)  POWER  = PVDDQ_KLM
  DL62  VCCD345(22)  POWER  = PVDDQ_KLM
  DL64  DDR4_CKE(2)  OUT  = M_L_CKE<2>
  DL66  RSVD(34)  BI  = TP_CPU1_RSVD_34
  DL68  VSS(160)  GROUND  = GND
  DL70  VSS(159)  GROUND  = GND
  DL72  DDR5_DQS_DN(2)  BI  = M_M_DQS_DN<2>
  DL74  VSS(158)  GROUND  = GND
  DL76  VSS(157)  GROUND  = GND
  DL78  VSS(156)  GROUND  = GND
  DL80  VSS(155)  GROUND  = GND
  DL82  DDR3_DQS_DN(2)  BI  = M_K_DQS_DN<2>
  DL84  DDR3_DQS_DP(10)  BI  = M_K_DQS_DP<10>
  DM3  PE1_TX_DN(6)  OUT  = TP_P3E_CPU1_PE1_MP_TXN<6>
  DM5  PE3_TX_DP(9)  OUT  = P3E_CPU1_PE3_MP_TXP<9>
  DM7  PE3_TX_DN(8)  OUT  = P3E_CPU1_PE3_MP_TXN<8>
  DM9  PE1_RX_DN(7)  IN  = TP_P3E_CPU1_PE1_MP_RXN<7>
  DM11  PE1_RX_DN(8)  IN  = TP_P3E_CPU1_PE1_RSR3_RXN<8>
  DM13  PE3_RX_DP(6)  IN  = P3E_CPU1_PE3_MP_RXP<6>
  DM15  VSS(154)  GROUND  = GND
  DM17  VCCIO(61)  POWER  = PVCCIO_CPU1
  DM19  VSS(1043)  GROUND  = GND
  DM21  UPI2_TX_DN(1)  OUT  = TP_CPU1_UPI2_RSVD_CC10
  DM23  DDR3_DQS_DN(16)  BI  = M_K_DQS_DN<16>
  DM25  VSS(152)  GROUND  = GND
  DM27  VSS(151)  GROUND  = GND
  DM29  DDR3_DQS_DN(15)  BI  = M_K_DQS_DN<15>
  DM31  VSS(150)  GROUND  = GND
  DM33  VSS(149)  GROUND  = GND
  DM35  DDR3_DQS_DP(14)  BI  = M_K_DQS_DP<14>
  DM37  VSS(148)  GROUND  = GND
  DM39  VSS(147)  GROUND  = GND
  DM41  DDR4_DQS_DP(13)  BI  = M_L_DQS_DP<13>
  DM45  DDR5_CS_N(6)  OUT  = M_M_CS_N<6>
  DM47  DDR4_ODT(3)  OUT  = M_L_ODT<3>
  DM49  DDR4_CS_N(5)  OUT  = M_L_CS_N<5>
  DM51  DDR4_MA(14)  OUT  = M_L_MA<14>
  DM53  DDR4_BA(0)  OUT  = M_L_BA<0>
  DM55  DDR4_CLK_DN(0)  OUT  = M_L_CLK_DN<0>
  DM57  DDR4_CLK_DN(2)  OUT  = M_L_CLK_DN<2>
  DM59  DDR4_MA(6)  OUT  = M_L_MA<6>
  DM61  DDR4_BG(1)  OUT  = M_L_BG<1>
  DM63  DDR4_CKE(0)  OUT  = M_L_CKE<0>
  DM65  VSS(146)  GROUND  = GND
  DM67  RSVD(33)  BI  = TP_CPU1_RSVD_33
  DM69  DDR5_DQ(18)  BI  = M_M_DQ<18>
  DM71  DDR5_DQ(23)  BI  = M_M_DQ<23>
  DM73  VSS(145)  GROUND  = GND
  DM75  DDR3_DQS_DP(12)  BI  = M_K_DQS_DP<12>
  DM77  VSS(144)  GROUND  = GND
  DM79  DDR3_DQ(16)  BI  = M_K_DQ<16>
  DM81  DDR3_DQS_DP(2)  BI  = M_K_DQS_DP<2>
  DM83  VSS(143)  GROUND  = GND
  DM85  DDR3_DQS_DN(10)  BI  = M_K_DQS_DN<10>
  DN2  VSS(142)  GROUND  = GND
  DN4  PE1_TX_DN(7)  OUT  = TP_P3E_CPU1_PE1_MP_TXN<7>
  DN6  PE3_TX_DP(8)  OUT  = P3E_CPU1_PE3_MP_TXP<8>
  DN8  VCCIO(62)  POWER  = PVCCIO_CPU1
  DN10  PE1_RX_DP(9)  IN  = TP_P3E_CPU1_PE1_RSR3_RXP<9>
  DN12  VSS(140)  GROUND  = GND
  DN14  PE3_RX_DN(6)  IN  = P3E_CPU1_PE3_MP_RXN<6>
  DN16  PE3_RX_DP(4)  IN  = P3E_CPU1_PE3_MP_RXP<4>
  DN18  VSS(1202)  GROUND  = GND
  DN20  UPI2_TX_DP(1)  OUT  = TP_CPU1_UPI2_RSVD_CB11
  DN22  VSS(139)  GROUND  = GND
  DN24  DDR3_DQ(56)  BI  = M_K_DQ<56>
  DN26  VSS(138)  GROUND  = GND
  DN28  DDR3_DQ(54)  BI  = M_K_DQ<54>
  DN30  DDR3_DQ(48)  BI  = M_K_DQ<48>
  DN32  VSS(137)  GROUND  = GND
  DN34  DDR3_DQ(46)  BI  = M_K_DQ<46>
  DN36  DDR3_DQ(40)  BI  = M_K_DQ<40>
  DN38  VSS(136)  GROUND  = GND
  DN40  DDR4_DQ(38)  BI  = M_L_DQ<38>
  DN42  DDR4_DQ(37)  BI  = M_L_DQ<37>
  DN44  VSS(1106)  GROUND  = GND
  DN46  DDR4_CS_N(7)  OUT  = M_L_CS_N<7>
  DN48  DDR4_ODT(1)  OUT  = M_L_ODT<1>
  DN50  DDR4_CS_N(1)  OUT  = M_L_CS_N<1>
  DN52  DDR4_MA(16)  OUT  = M_L_MA<16>
  DN54  DDR4_CLK_DP(0)  OUT  = M_L_CLK_DP<0>
  DN56  DDR4_CLK_DP(2)  OUT  = M_L_CLK_DP<2>
  DN58  DDR4_MA(5)  OUT  = M_L_MA<5>
  DN60  DDR4_MA(12)  OUT  = M_L_MA<12>
  DN62  RSVD(32)  BI  = TP_CPU1_RSVD_32
  DN64  DDR4_CKE(1)  OUT  = M_L_CKE<1>
  DN66  RSVD(31)  BI  = TP_CPU1_RSVD_31
  DN68  VSS(135)  GROUND  = GND
  DN70  DDR5_DQ(19)  BI  = M_M_DQ<19>
  DN72  VSS(134)  GROUND  = GND
  DN74  DDR3_DQ(30)  BI  = M_K_DQ<30>
  DN76  DDR3_DQ(24)  BI  = M_K_DQ<24>
  DN78  VSS(133)  GROUND  = GND
  DN80  DDR3_DQS_DN(11)  BI  = M_K_DQS_DN<11>
  DN82  DDR3_DQ(23)  BI  = M_K_DQ<23>
  DN84  DDR3_DQS_DN(1)  BI  = M_K_DQS_DN<1>
  DP3  PE1_TX_DP(7)  OUT  = TP_P3E_CPU1_PE1_MP_TXP<7>
  DP5  PE3_TX_DN(9)  OUT  = P3E_CPU1_PE3_MP_TXN<9>
  DP7  PE3_TX_DP(7)  OUT  = P3E_CPU1_PE3_MP_TXP<7>
  DP9  VSS(1213)  GROUND  = GND
  DP11  PE1_RX_DN(9)  IN  = TP_P3E_CPU1_PE1_RSR3_RXN<9>
  DP13  PE1_RX_DP(11)  IN  = TP_P3E_CPU1_PE1_RSR3_RXP<11>
  DP15  PE3_RX_DP(5)  IN  = P3E_CPU1_PE3_MP_RXP<5>
  DP17  RSVD(30)  BI  = TP_CPU1_RSVD_30
  DP19  VCCIO(63)  POWER  = PVCCIO_CPU1
  DP21  UPI2_TX_DP(0)  OUT  = TP_CPU1_UPI2_RSVD_CA12
  DP23  DDR3_DQS_DP(16)  BI  = M_K_DQS_DP<16>
  DP25  DDR3_DQ(60)  BI  = M_K_DQ<60>
  DP27  DDR3_DQ(50)  BI  = M_K_DQ<50>
  DP29  DDR3_DQS_DP(15)  BI  = M_K_DQS_DP<15>
  DP31  DDR3_DQ(52)  BI  = M_K_DQ<52>
  DP33  DDR3_DQ(42)  BI  = M_K_DQ<42>
  DP35  DDR3_DQS_DN(14)  BI  = M_K_DQS_DN<14>
  DP37  DDR3_DQ(44)  BI  = M_K_DQ<44>
  DP39  DDR4_DQ(34)  BI  = M_L_DQ<34>
  DP41  DDR4_DQS_DN(13)  BI  = M_L_DQS_DN<13>
  DP45  VSS(1203)  GROUND  = GND
  DP47  VSS(1204)  GROUND  = GND
  DP49  VSS(1205)  GROUND  = GND
  DP51  VSS(1206)  GROUND  = GND
  DP53  VSS(1207)  GROUND  = GND
  DP55  VSS(1208)  GROUND  = GND
  DP57  VSS(1209)  GROUND  = GND
  DP59  VSS(1210)  GROUND  = GND
  DP61  VSS(1211)  GROUND  = GND
  DP63  VSS(1212)  GROUND  = GND
  DP65  RSVD(29)  BI  = TP_CPU1_RSVD_29
  DP67  VSS(132)  GROUND  = GND
  DP69  VSS(131)  GROUND  = GND
  DP71  VSS(130)  GROUND  = GND
  DP73  DDR3_DQ(26)  BI  = M_K_DQ<26>
  DP75  DDR3_DQS_DN(12)  BI  = M_K_DQS_DN<12>
  DP77  DDR3_DQ(28)  BI  = M_K_DQ<28>
  DP79  DDR3_DQS_DP(11)  BI  = M_K_DQS_DP<11>
  DP81  VSS(129)  GROUND  = GND
  DP83  VSS(128)  GROUND  = GND
  DP85  DDR3_DQS_DP(1)  BI  = M_K_DQS_DP<1>
  DR2  VCCIO(65)  POWER  = PVCCIO_CPU1
  DR4  PE1_TX_DP(8)  OUT  = TP_P3E_CPU1_PE1_RSR3_TXP<8>
  DR6  VSS(126)  GROUND  = GND
  DR8  PE3_TX_DN(7)  OUT  = P3E_CPU1_PE3_MP_TXN<7>
  DR10  VCCIO(64)  POWER  = PVCCIO_CPU1
  DR12  PE1_RX_DP(10)  IN  = TP_P3E_CPU1_PE1_RSR3_RXP<10>
  DR14  PE3_RX_DN(5)  IN  = P3E_CPU1_PE3_MP_RXN<5>
  DR16  PE3_RX_DN(4)  IN  = P3E_CPU1_PE3_MP_RXN<4>
  DR18  PE3_RX_DP(3)  IN  = P3E_CPU1_PE3_MP_RXP<3>
  DR20  VSS(123)  GROUND  = GND
  DR22  VSS(122)  GROUND  = GND
  DR24  VSS(121)  GROUND  = GND
  DR26  VSS(120)  GROUND  = GND
  DR28  VSS(119)  GROUND  = GND
  DR30  VSS(118)  GROUND  = GND
  DR32  VSS(117)  GROUND  = GND
  DR34  VSS(116)  GROUND  = GND
  DR36  VSS(115)  GROUND  = GND
  DR38  VSS(114)  GROUND  = GND
  DR40  VSS(113)  GROUND  = GND
  DR42  VSS(112)  GROUND  = GND
  DR44  RSVD(28)  BI  = TP_CPU1_RSVD_28
  DR46  DDR4_CS_N(2)  OUT  = M_L_CS_N<2>
  DR48  DDR4_MA(17)  OUT  = M_L_MA<17>
  DR50  DDR4_ODT(0)  OUT  = M_L_ODT<0>
  DR52  DDR4_MA(15)  OUT  = M_L_MA<15>
  DR54  DDR4_CLK_DN(1)  OUT  = M_L_CLK_DN<1>
  DR56  DDR4_CLK_DP(3)  OUT  = M_L_CLK_DP<3>
  DR58  DDR4_MA(3)  OUT  = M_L_MA<3>
  DR60  DDR4_MA(11)  OUT  = M_L_MA<11>
  DR62  DDR4_ACT_N  OUT  = M_L_ACT_N
  DR64  DDR4_CKE(3)  OUT  = M_L_CKE<3>
  DR66  VSS(111)  GROUND  = GND
  DR68  VSS(110)  GROUND  = GND
  DR70  VSS(109)  GROUND  = GND
  DR72  VSS(108)  GROUND  = GND
  DR74  VSS(107)  GROUND  = GND
  DR76  VSS(106)  GROUND  = GND
  DR78  VSS(105)  GROUND  = GND
  DR80  DDR3_DQ(22)  BI  = M_K_DQ<22>
  DR82  DDR3_DQ(19)  BI  = M_K_DQ<19>
  DR84  DDR3_DQ(14)  BI  = M_K_DQ<14>
  DT3  VSS(104)  GROUND  = GND
  DT5  PE1_TX_DN(8)  OUT  = TP_P3E_CPU1_PE1_RSR3_TXN<8>
  DT7  PE1_TX_DP(12)  OUT  = TP_P3E_CPU1_PE1_RSR3_TXP<12>
  DT9  PE3_TX_DP(6)  OUT  = P3E_CPU1_PE3_MP_TXP<6>
  DT11  PE1_RX_DN(10)  IN  = TP_P3E_CPU1_PE1_RSR3_RXN<10>
  DT13  PE1_RX_DN(11)  IN  = TP_P3E_CPU1_PE1_RSR3_RXN<11>
  DT15  PE1_RX_DP(15)  IN  = TP_P3E_CPU1_PE1_RSR3_RXP<15>
  DT17  VSS(103)  GROUND  = GND
  DT19  PE3_RX_DN(3)  IN  = P3E_CPU1_PE3_MP_RXN<3>
  DT21  UPI2_TX_DN(0)  OUT  = TP_CPU1_UPI2_RSVD_CC12
  DT23  DDR3_DQS_DP(7)  BI  = M_K_DQS_DP<7>
  DT25  DDR3_DQ(61)  BI  = M_K_DQ<61>
  DT27  DDR3_DQ(51)  BI  = M_K_DQ<51>
  DT29  DDR3_DQS_DP(6)  BI  = M_K_DQS_DP<6>
  DT31  DDR3_DQ(53)  BI  = M_K_DQ<53>
  DT33  DDR3_DQ(43)  BI  = M_K_DQ<43>
  DT35  DDR3_DQS_DP(5)  BI  = M_K_DQS_DP<5>
  DT37  DDR3_DQ(45)  BI  = M_K_DQ<45>
  DT39  DDR4_DQ(35)  BI  = M_L_DQ<35>
  DT41  DDR4_DQS_DP(4)  BI  = M_L_DQS_DP<4>
  DT45  DDR4_CS_N(6)  OUT  = M_L_CS_N<6>
  DT47  DDR4_CID(2)  OUT  = M_L_C<2>
  DT49  DDR4_ODT(2)  OUT  = M_L_ODT<2>
  DT51  DDR4_MA(13)  OUT  = M_L_MA<13>
  DT53  DDR4_CLK_DP(1)  OUT  = M_L_CLK_DP<1>
  DT55  DDR4_MA(10)  OUT  = M_L_MA<10>
  DT57  DDR4_CLK_DN(3)  OUT  = M_L_CLK_DN<3>
  DT59  DDR4_MA(4)  OUT  = M_L_MA<4>
  DT61  DDR4_ALERT_N  IN  = M_L_ALERT_N
  DT63  DDR3_MA(12)  OUT  = M_K_MA<12>
  DT65  VSS(101)  GROUND  = GND
  DT67  DDR4_DQS_DP(17)  BI  = M_L_DQS_DP<17>
  DT69  VSS(100)  GROUND  = GND
  DT71  RSVD(27)  BI  = TP_CPU1_RSVD_27
  DT73  DDR3_DQ(27)  BI  = M_K_DQ<27>
  DT75  DDR3_DQS_DP(3)  BI  = M_K_DQS_DP<3>
  DT77  DDR3_DQ(29)  BI  = M_K_DQ<29>
  DT79  VSS(99)  GROUND  = GND
  DT81  DDR3_DQ(18)  BI  = M_K_DQ<18>
  DT83  VSS(98)  GROUND  = GND
  DT85  VSS(97)  GROUND  = GND
  DU2  PE1_TX_DP(9)  OUT  = TP_P3E_CPU1_PE1_RSR3_TXP<9>
  DU4  PE1_TX_DP(10)  OUT  = TP_P3E_CPU1_PE1_RSR3_TXP<10>
  DU6  PE1_TX_DN(11)  OUT  = TP_P3E_CPU1_PE1_RSR3_TXN<11>
  DU8  PE3_TX_DN(6)  OUT  = P3E_CPU1_PE3_MP_TXN<6>
  DU10  VSS(96)  GROUND  = GND
  DU12  PE1_RX_DP(12)  IN  = TP_P3E_CPU1_PE1_RSR3_RXP<12>
  DU14  VSS(95)  GROUND  = GND
  DU16  PE1_RX_DN(15)  IN  = TP_P3E_CPU1_PE1_RSR3_RXN<15>
  DU18  PE3_RX_DP(1)  IN  = P3E_CPU1_PE3_MP_RXP<1>
  DU20  VCCIO(66)  POWER  = PVCCIO_CPU1
  DU22  VSS(93)  GROUND  = GND
  DU24  DDR3_DQ(57)  BI  = M_K_DQ<57>
  DU26  VSS(92)  GROUND  = GND
  DU28  DDR3_DQ(55)  BI  = M_K_DQ<55>
  DU30  DDR3_DQ(49)  BI  = M_K_DQ<49>
  DU32  VSS(91)  GROUND  = GND
  DU34  DDR3_DQ(47)  BI  = M_K_DQ<47>
  DU36  DDR3_DQ(41)  BI  = M_K_DQ<41>
  DU38  VSS(90)  GROUND  = GND
  DU40  DDR4_DQ(39)  BI  = M_L_DQ<39>
  DU42  DDR4_DQ(32)  BI  = M_L_DQ<32>
  DU44  RSVD(26)  BI  = TP_CPU1_RSVD_26
  DU46  VCCD345(21)  POWER  = PVDDQ_KLM
  DU48  VCCD345(20)  POWER  = PVDDQ_KLM
  DU50  VCCD345(19)  POWER  = PVDDQ_KLM
  DU52  VCCD345(18)  POWER  = PVDDQ_KLM
  DU54  VCCD345(17)  POWER  = PVDDQ_KLM
  DU56  VCCD345(16)  POWER  = PVDDQ_KLM
  DU58  VCCD345(15)  POWER  = PVDDQ_KLM
  DU60  VCCD345(14)  POWER  = PVDDQ_KLM
  DU62  VCCD345(13)  POWER  = PVDDQ_KLM
  DU64  VCCD345(12)  POWER  = PVDDQ_KLM
  DU66  DDR4_ECC(6)  BI  = M_L_ECC<6>
  DU68  DDR4_ECC(4)  BI  = M_L_ECC<4>
  DU70  VSS(89)  GROUND  = GND
  DU72  VSS(88)  GROUND  = GND
  DU74  DDR3_DQ(31)  BI  = M_K_DQ<31>
  DU76  DDR3_DQ(25)  BI  = M_K_DQ<25>
  DU78  VSS(87)  GROUND  = GND
  DU80  VSS(86)  GROUND  = GND
  DU82  VSS(85)  GROUND  = GND
  DU84  VSS(84)  GROUND  = GND
  DV3  PE1_TX_DN(9)  OUT  = TP_P3E_CPU1_PE1_RSR3_TXN<9>
  DV5  PE1_TX_DP(11)  OUT  = TP_P3E_CPU1_PE1_RSR3_TXP<11>
  DV7  PE1_TX_DN(12)  OUT  = TP_P3E_CPU1_PE1_RSR3_TXN<12>
  DV9  PE3_TX_DP(5)  OUT  = P3E_CPU1_PE3_MP_TXP<5>
  DV11  VCCIO(3)  POWER  = PVCCIO_CPU1
  DV13  PE1_RX_DN(12)  IN  = TP_P3E_CPU1_PE1_RSR3_RXN<12>
  DV15  PE1_RX_DP(14)  IN  = TP_P3E_CPU1_PE1_RSR3_RXP<14>
  DV17  PE3_RX_DP(2)  IN  = P3E_CPU1_PE3_MP_RXP<2>
  DV19  VSS(1214)  GROUND  = GND
  DV21  VSS(83)  GROUND  = GND
  DV23  DDR3_DQS_DN(7)  BI  = M_K_DQS_DN<7>
  DV25  VSS(82)  GROUND  = GND
  DV27  VSS(81)  GROUND  = GND
  DV29  DDR3_DQS_DN(6)  BI  = M_K_DQS_DN<6>
  DV31  VSS(80)  GROUND  = GND
  DV33  VSS(79)  GROUND  = GND
  DV35  DDR3_DQS_DN(5)  BI  = M_K_DQS_DN<5>
  DV37  VSS(78)  GROUND  = GND
  DV39  VSS(77)  GROUND  = GND
  DV41  DDR4_DQS_DN(4)  BI  = M_L_DQS_DN<4>
  DV45  DDR3_CS_N(6)  OUT  = M_K_CS_N<6>
  DV47  DDR3_CID(2)  OUT  = M_K_C<2>
  DV49  DDR3_MA(15)  OUT  = M_K_MA<15>
  DV51  DDR4_CS_N(0)  OUT  = M_L_CS_N<0>
  DV53  DDR4_PAR  OUT  = M_L_PAR
  DV55  DDR4_BA(1)  OUT  = M_L_BA<1>
  DV57  DDR4_MA(2)  OUT  = M_L_MA<2>
  DV59  DDR4_MA(9)  OUT  = M_L_MA<9>
  DV61  RSVD(25)  BI  = TP_CPU1_RSVD_25
  DV63  DDR345_RESET_N  OUT  = M_KLM_RST_N
  DV65  DDR4_ECC(2)  BI  = M_L_ECC<2>
  DV67  DDR4_DQS_DN(17)  BI  = M_L_DQS_DN<17>
  DV69  DDR4_ECC(5)  BI  = M_L_ECC<5>
  DV71  RSVD(24)  BI  = TP_CPU1_RSVD_24
  DV73  VSS(76)  GROUND  = GND
  DV75  DDR3_DQS_DN(3)  BI  = M_K_DQS_DN<3>
  DV77  VSS(75)  GROUND  = GND
  DV79  DDR4_DQS_DP(11)  BI  = M_L_DQS_DP<11>
  DV81  VSS(74)  GROUND  = GND
  DV83  DDR3_DQ(10)  BI  = M_K_DQ<10>
  DV85  DDR3_DQ(15)  BI  = M_K_DQ<15>
  DW2  VSS(1239)  GROUND  = GND
  DW4  PE1_TX_DN(10)  OUT  = TP_P3E_CPU1_PE1_RSR3_TXN<10>
  DW6  PE1_TX_DP(13)  OUT  = TP_P3E_CPU1_PE1_RSR3_TXP<13>
  DW8  VSS(58)  GROUND  = GND
  DW10  PE3_TX_DN(5)  OUT  = P3E_CPU1_PE3_MP_TXN<5>
  DW12  VSS(73)  GROUND  = GND
  DW14  PE1_RX_DN(13)  IN  = TP_P3E_CPU1_PE1_RSR3_RXN<13>
  DW16  PE3_RX_DN(2)  IN  = P3E_CPU1_PE3_MP_RXN<2>
  DW18  PE3_RX_DN(1)  IN  = P3E_CPU1_PE3_MP_RXN<1>
  DW20  VSS(72)  GROUND  = GND
  DW22  DDR3_DQ(63)  BI  = M_K_DQ<63>
  DW24  VSS(71)  GROUND  = GND
  DW26  DDR4_DQS_DP(15)  BI  = M_L_DQS_DP<15>
  DW28  VSS(70)  GROUND  = GND
